# TIMECARD (Time Appliance Project (Time Card)) — schematic netlist excerpt (pin names and nets, part order shuffled) for the footprints in the layout excerpt that follows; sources: Cadence DE-HDL packaged netlist, KiCad conversion of R4006-B0001-02_R01.brd

SP44  NULL  pkg DUMMY  page 34

U15  74HCT2G125DP_TSSOP8  NC7WV125K8X  pkg SOP8_091_P0197_H035  page 23
  \1oe*\  = SMA1_SIG_OUT_BF_EN_N
  \1a\  = UNNAMED_12_74HCT2G125DPTSSOP8_6
  \2y\  = BF_ANT1_IN
  GND  = SG
  \2a\  = BF_SMA1_SIG_IO_CONN
  \1y\  = BF_SMA1_SIG_IO_CONN
  \2oe*\  = SMA1_SIG_IN_BF_EN_N
  VCC  = XP3R3V_FPGA

TP54  TP_PIONT  pkg TP010CT020B030_PTH  page 25 : \1\ = XP1R0V_FPGA

(kicad_pcb
	(version 20260206)
	(generator "pcbnew")
	(generator_version "10.0")
	(general
		(thickness 1.6)
		(legacy_teardrops no)
	)
	(paper "A4")
	(title_block
		(title "timecard-production-celestica-r4006 — R4006-B0001-02_R01.brd")
		(comment 1 "Time Appliance Project (Time Card) / footprints 35-37 of 1113")
	)
	(layers
		(0 "F.Cu" signal "TOP")
		(4 "In1.Cu" signal "L02_GND1")
		(6 "In2.Cu" signal "L03_SIG1")
		(8 "In3.Cu" signal "L04_GND2")
		(10 "In4.Cu" signal "L05_VCC1")
		(12 "In5.Cu" signal "L06_VCC2")
		(14 "In6.Cu" signal "L07_GND3")
		(16 "In7.Cu" signal "L08_SIG2")
		(18 "In8.Cu" signal "L09_GND4")
		(2 "B.Cu" signal "BOTTOM")
		(9 "F.Adhes" user "F.Adhesive")
		(11 "B.Adhes" user "B.Adhesive")
		(13 "F.Paste" user "Package Geometry/Pastemask Top")
		(15 "B.Paste" user "Package Geometry/Pastemask Bottom")
		(5 "F.SilkS" user "Ref Des/Silkscreen Top")
		(7 "B.SilkS" user "Ref Des/Silkscreen Bottom")
		(1 "F.Mask" user "Board Geometry/Soldermask Top")
		(3 "B.Mask" user "Board Geometry/Soldermask Bottom")
		(17 "Dwgs.User" user "User.Drawings")
		(19 "Cmts.User" user "User.Comments")
		(21 "Eco1.User" user "User.Eco1")
		(23 "Eco2.User" user "User.Eco2")
		(25 "Edge.Cuts" user "Board Geometry/Outline")
		(27 "Margin" user)
		(31 "F.CrtYd" user "Package Geometry/Place Bound Top")
		(29 "B.CrtYd" user "Package Geometry/Place Bound Bottom")
		(35 "F.Fab" user "Ref Des/Assembly Top")
		(33 "B.Fab" user "Ref Des/Assembly Bottom")
	)
	(footprint ""
		(layer "F.Cu")
		(at 13.899896 -61.60008 -90)
		(property "Reference" "U15"
			(at -0.88392 2.430526 90)
			(unlocked yes)
			(layer "F.SilkS")
			(effects
				(font
					(size 0.7874 0.5842)
					(thickness 0.1524)
				)
			)
		)
		(property "Value" ""
			(at 0 0 270)
			(layer "F.Fab")
			(effects
				(font
					(size 1.27 1.27)
				)
			)
		)
		(property "User Part Number" "PARTNUM*"
			(at 0 3.6068 270)
			(unlocked yes)
			(layer "Cmts.User")
			(hide yes)
			(effects
				(font
					(size 0.7874 0.5842)
					(thickness 0.1524)
				)
			)
		)
		(property "Device Type" "74HCT2G125DP_TSSOP8-G220-00055A"
			(at 0 2.413 270)
			(unlocked yes)
			(layer "F.Fab")
			(hide yes)
			(effects
				(font
					(size 0.7874 0.5842)
					(thickness 0.1524)
				)
			)
		)
		(duplicate_pad_numbers_are_jumpers no)
		(fp_line
			(start -2.426716 1.304036)
			(end -2.426716 -1.304036)
			(stroke
				(width 0.1)
				(type default)
			)
			(layer "F.SilkS")
		)
		(fp_line
			(start 2.426716 1.304036)
			(end -2.426716 1.304036)
			(stroke
				(width 0.1)
				(type default)
			)
			(layer "F.SilkS")
		)
		(fp_line
			(start -2.426716 -1.304036)
			(end 2.426716 -1.304036)
			(stroke
				(width 0.1)
				(type default)
			)
			(layer "F.SilkS")
		)
		(fp_line
			(start 2.426716 -1.304036)
			(end 2.426716 1.304036)
			(stroke
				(width 0.1)
				(type default)
			)
			(layer "F.SilkS")
		)
		(fp_poly
			(pts
				(arc
					(start -3.21437 -1.465326)
					(mid -3.21437 -0.703326)
					(end -3.21437 -1.465326)
				)
			)
			(stroke
				(width 0)
				(type default)
			)
			(fill yes)
			(layer "F.SilkS")
		)
		(fp_poly
			(pts
				(xy -2.680716 1.558036) (xy 2.680716 1.558036) (xy 2.680716 -1.558036) (xy -2.680716 -1.558036)
			)
			(stroke
				(width 0)
				(type default)
			)
			(fill no)
			(layer "F.CrtYd")
		)
		(fp_line
			(start -1.199896 1.050036)
			(end 1.199896 1.050036)
			(stroke
				(width 0.1)
				(type default)
			)
			(layer "F.Fab")
		)
		(fp_line
			(start 1.199896 1.050036)
			(end 1.199896 -1.050036)
			(stroke
				(width 0.1)
				(type default)
			)
			(layer "F.Fab")
		)
		(fp_line
			(start -1.199896 -1.050036)
			(end -1.199896 1.050036)
			(stroke
				(width 0.1)
				(type default)
			)
			(layer "F.Fab")
		)
		(fp_line
			(start 1.199896 -1.050036)
			(end -1.199896 -1.050036)
			(stroke
				(width 0.1)
				(type default)
			)
			(layer "F.Fab")
		)
		(fp_poly
			(pts
				(arc
					(start -2.02692 -1.721104)
					(mid -2.02692 -0.959104)
					(end -2.02692 -1.721104)
				)
			)
			(stroke
				(width 0)
				(type default)
			)
			(fill yes)
			(layer "F.Fab")
		)
		(fp_text user "4"
			(at -1.53797 1.707896 0)
			(unlocked yes)
			(layer "F.SilkS")
			(effects
				(font
					(size 0.635 0.4064)
					(thickness 0.1524)
				)
			)
		)
		(fp_text user "5"
			(at 2.78003 1.580896 0)
			(unlocked yes)
			(layer "F.SilkS")
			(effects
				(font
					(size 0.635 0.4064)
					(thickness 0.1524)
				)
			)
		)
		(fp_text user "8"
			(at 2.70383 -1.594104 0)
			(unlocked yes)
			(layer "F.SilkS")
			(effects
				(font
					(size 0.635 0.4064)
					(thickness 0.1524)
				)
			)
		)
		(fp_text user "5"
			(at 1.816608 1.326896 0)
			(unlocked yes)
			(layer "F.Fab")
			(effects
				(font
					(size 0.7874 0.5842)
					(thickness 0.1524)
				)
			)
		)
		(fp_text user "4"
			(at -1.993392 1.199896 0)
			(unlocked yes)
			(layer "F.Fab")
			(effects
				(font
					(size 0.7874 0.5842)
					(thickness 0.1524)
				)
			)
		)
		(fp_text user "8"
			(at 1.94945 -1.340104 0)
			(unlocked yes)
			(layer "F.Fab")
			(effects
				(font
					(size 0.7874 0.5842)
					(thickness 0.1524)
				)
			)
		)
		(pad "1" smd rect
			(at -1.690116 -0.749808 270)
			(size 0.9652 0.3048)
			(layers "F.Cu" "F.Mask" "F.Paste")
			(net "SMA1_SIG_OUT_BF_EN_N")
		)
		(pad "2" smd rect
			(at -1.690116 -0.249936 270)
			(size 0.9652 0.3048)
			(layers "F.Cu" "F.Mask" "F.Paste")
			(net "UNNAMED_12_74HCT2G125DPTSSOP8_6")
		)
		(pad "3" smd rect
			(at -1.690116 0.249936 270)
			(size 0.9652 0.3048)
			(layers "F.Cu" "F.Mask" "F.Paste")
			(net "BF_ANT1_IN")
		)
		(pad "4" smd rect
			(at -1.690116 0.749808 270)
			(size 0.9652 0.3048)
			(layers "F.Cu" "F.Mask" "F.Paste")
			(net "SG")
		)
		(pad "5" smd rect
			(at 1.690116 0.749808 270)
			(size 0.9652 0.3048)
			(layers "F.Cu" "F.Mask" "F.Paste")
			(net "BF_SMA1_SIG_IO_CONN")
		)
		(pad "6" smd rect
			(at 1.690116 0.249936 270)
			(size 0.9652 0.3048)
			(layers "F.Cu" "F.Mask" "F.Paste")
			(net "BF_SMA1_SIG_IO_CONN")
		)
		(pad "7" smd rect
			(at 1.690116 -0.249936 270)
			(size 0.9652 0.3048)
			(layers "F.Cu" "F.Mask" "F.Paste")
			(net "SMA1_SIG_IN_BF_EN_N")
		)
		(pad "8" smd rect
			(at 1.690116 -0.749808 270)
			(size 0.9652 0.3048)
			(layers "F.Cu" "F.Mask" "F.Paste")
			(net "XP3R3V_FPGA")
		)
	)
	(footprint ""
		(layer "F.Cu")
		(at 57.15 -122.047)
		(property "Reference" "SP44"
			(at 0 0 0)
			(layer "F.SilkS")
			(hide yes)
			(effects
				(font
					(size 1.27 1.27)
				)
			)
		)
		(property "Value" ""
			(at 0 0 0)
			(layer "F.Fab")
			(effects
				(font
					(size 1.27 1.27)
				)
			)
		)
		(duplicate_pad_numbers_are_jumpers no)
	)
	(footprint ""
		(layer "F.Cu")
		(at 141.732 -41.021)
		(property "Reference" "TP54"
			(at -1.8542 1.18237 0)
			(unlocked yes)
			(layer "F.SilkS")
			(effects
				(font
					(size 0.7874 0.5842)
					(thickness 0.1524)
				)
				(justify left)
			)
		)
		(property "Value" ""
			(at 0 0 0)
			(layer "F.Fab")
			(effects
				(font
					(size 1.27 1.27)
				)
			)
		)
		(property "Device Type" "TP_PIONT-TP010CT020B030_PTH-TPA"
			(at -1.341882 0.996696 0)
			(unlocked yes)
			(layer "F.Fab")
			(hide yes)
			(effects
				(font
					(size 0.7874 0.5842)
					(thickness 0.1524)
				)
				(justify left)
			)
		)
		(duplicate_pad_numbers_are_jumpers no)
		(fp_poly
			(pts
				(arc
					(start 0.889 0)
					(mid -0.889 0)
					(end 0.889 0)
				)
			)
			(stroke
				(width 0)
				(type default)
			)
			(fill no)
			(layer "B.CrtYd")
		)
		(fp_poly
			(pts
				(arc
					(start 0.889 0)
					(mid -0.889 0)
					(end 0.889 0)
				)
			)
			(stroke
				(width 0)
				(type default)
			)
			(fill no)
			(layer "F.CrtYd")
		)
		(pad "1" thru_hole circle
			(at 0 0)
			(size 0.508 0.508)
			(drill 0.254)
			(layers "*.Cu" "*.Mask")
			(remove_unused_layers no)
			(net "XP1R0V_FPGA")
			(clearance 0.1016)
			(padstack
				(mode front_inner_back)
				(layer "Inner"
					(shape circle)
					(size 0.508 0.508)
					(clearance 0.1016)
				)
				(layer "B.Cu"
					(shape circle)
					(size 0.762 0.762)
					(clearance -0.0254)
				)
			)
		)
	)
)
